# BASEBOARD_FAB2 (Tioga Pass) — schematic netlist excerpt (pin names and nets, part order shuffled) for the footprints in the layout excerpt that follows; sources: Cadence DE-HDL packaged netlist, KiCad conversion of Wiwynn_Tioga_Pass_MB.brd

R8B18  RES  4.75K 1% CHIP  pkg 0402  page 91 : A = PVPP_ABC ; B = LED_HFI1_CPU0_N
C8A12  CAP  47UF 4V 20% X6S  pkg 0805  page 237 : A = P1V8_PCH_STBY ; B = GND
R25W108  RES  4.75K 1% EMPTY  pkg 0402  page 150 : A = P3V3_STBY ; B = RMII_BMC_OCP_TXD1_R

(kicad_pcb
	(version 20260206)
	(generator "pcbnew")
	(generator_version "10.0")
	(general
		(thickness 1.6)
		(legacy_teardrops no)
	)
	(paper "A4")
	(title_block
		(title "Wiwynn_Tioga_Pass_MB.brd")
		(comment 1 "Tioga Pass / footprints 1884-1886 of 4770")
	)
	(layers
		(0 "F.Cu" signal "TOP")
		(4 "In1.Cu" signal "L2GND")
		(6 "In2.Cu" signal "L3")
		(8 "In3.Cu" signal "L4GND")
		(10 "In4.Cu" signal "L5")
		(12 "In5.Cu" signal "L6GND")
		(14 "In6.Cu" signal "L7VCC")
		(16 "In7.Cu" signal "L8VCC")
		(18 "In8.Cu" signal "L9GND")
		(20 "In9.Cu" signal "L10")
		(22 "In10.Cu" signal "L11GND")
		(24 "In11.Cu" signal "L12")
		(26 "In12.Cu" signal "L13GND")
		(2 "B.Cu" signal "BOTTOM")
		(9 "F.Adhes" user "F.Adhesive")
		(11 "B.Adhes" user "B.Adhesive")
		(13 "F.Paste" user "Package Geometry/Pastemask Top")
		(15 "B.Paste" user "Package Geometry/Pastemask Bottom")
		(5 "F.SilkS" user "Ref Des/Silkscreen Top")
		(7 "B.SilkS" user "Ref Des/Silkscreen Bottom")
		(1 "F.Mask" user "Board Geometry/Soldermask Top")
		(3 "B.Mask" user "Board Geometry/Soldermask Bottom")
		(17 "Dwgs.User" user "User.Drawings")
		(19 "Cmts.User" user "User.Comments")
		(21 "Eco1.User" user "User.Eco1")
		(23 "Eco2.User" user "User.Eco2")
		(25 "Edge.Cuts" user "Board Geometry/Outline")
		(27 "Margin" user)
		(31 "F.CrtYd" user "Package Geometry/Place Bound Top")
		(29 "B.CrtYd" user "Package Geometry/Place Bound Bottom")
		(35 "F.Fab" user "Ref Des/Assembly Top")
		(33 "B.Fab" user "Ref Des/Assembly Bottom")
	)
	(footprint ""
		(layer "F.Cu")
		(at 421.005 -117.4877 180)
		(property "Reference" "R8B18"
			(at 0 0 180)
			(layer "F.SilkS")
			(hide yes)
			(effects
				(font
					(size 1.27 1.27)
				)
			)
		)
		(property "Value" ""
			(at 0 0 180)
			(layer "F.Fab")
			(effects
				(font
					(size 1.27 1.27)
				)
			)
		)
		(duplicate_pad_numbers_are_jumpers no)
		(fp_poly
			(pts
				(xy -0.2794 -0.1016) (xy 0.2794 -0.1016) (xy 0.2794 0.9906) (xy -0.2794 0.9906)
			)
			(stroke
				(width 0)
				(type default)
			)
			(fill no)
			(layer "F.CrtYd")
		)
		(fp_line
			(start 0.2794 0.9906)
			(end 0.2794 -0.1016)
			(stroke
				(width 0.1)
				(type default)
			)
			(layer "F.Fab")
		)
		(fp_line
			(start 0.2794 -0.1016)
			(end -0.2794 -0.1016)
			(stroke
				(width 0.1)
				(type default)
			)
			(layer "F.Fab")
		)
		(fp_line
			(start -0.2794 0.9906)
			(end 0.2794 0.9906)
			(stroke
				(width 0.1)
				(type default)
			)
			(layer "F.Fab")
		)
		(fp_line
			(start -0.2794 -0.1016)
			(end -0.2794 0.9906)
			(stroke
				(width 0.1)
				(type default)
			)
			(layer "F.Fab")
		)
		(pad "1" smd rect
			(at 0 0 180)
			(size 0.508 0.508)
			(layers "F.Cu" "F.Mask" "F.Paste")
			(net "PVPP_ABC")
		)
		(pad "2" smd rect
			(at 0 0.889 180)
			(size 0.508 0.508)
			(layers "F.Cu" "F.Mask" "F.Paste")
			(net "LED_HFI1_CPU0_N")
		)
		(zone
			(layer "F.Cu")
			(hatch none 0.5)
			(connect_pads
				(clearance 0)
			)
			(min_thickness 0.25)
			(keepout
				(tracks allowed)
				(vias not_allowed)
				(pads allowed)
				(copperpour not_allowed)
				(footprints allowed)
			)
			(placement
				(enabled no)
				(sheetname "")
			)
			(fill
				(thermal_gap 0.5)
				(thermal_bridge_width 0.5)
				(island_removal_mode 0)
			)
			(polygon
				(pts
					(xy 421.259 -117.7417) (xy 420.751 -117.7417) (xy 420.750746 -118.1227) (xy 421.259254 -118.1227)
				)
			)
		)
		(zone
			(layer "F.Cu")
			(hatch none 0.5)
			(connect_pads
				(clearance 0)
			)
			(min_thickness 0.25)
			(keepout
				(tracks not_allowed)
				(vias allowed)
				(pads allowed)
				(copperpour not_allowed)
				(footprints allowed)
			)
			(placement
				(enabled no)
				(sheetname "")
			)
			(fill
				(thermal_gap 0.5)
				(thermal_bridge_width 0.5)
				(island_removal_mode 0)
			)
			(polygon
				(pts
					(xy 421.259254 -118.1227) (xy 420.750746 -118.1227) (xy 420.751 -117.7417) (xy 421.259 -117.7417)
				)
			)
		)
	)
	(footprint ""
		(layer "F.Cu")
		(at 403.154388 -28.490926 180)
		(property "Reference" "R25W108"
			(at -0.8382 -0.67818 180)
			(unlocked yes)
			(layer "F.SilkS")
			(effects
				(font
					(size 0.4064 0.254)
					(thickness 0.1524)
				)
				(justify left)
			)
		)
		(property "Value" ""
			(at 0 0 180)
			(layer "F.Fab")
			(effects
				(font
					(size 1.27 1.27)
				)
			)
		)
		(duplicate_pad_numbers_are_jumpers no)
		(fp_poly
			(pts
				(xy -0.2794 -0.1016) (xy 0.2794 -0.1016) (xy 0.2794 0.9906) (xy -0.2794 0.9906)
			)
			(stroke
				(width 0)
				(type default)
			)
			(fill no)
			(layer "F.CrtYd")
		)
		(fp_line
			(start 0.2794 0.9906)
			(end 0.2794 -0.1016)
			(stroke
				(width 0.1)
				(type default)
			)
			(layer "F.Fab")
		)
		(fp_line
			(start 0.2794 -0.1016)
			(end -0.2794 -0.1016)
			(stroke
				(width 0.1)
				(type default)
			)
			(layer "F.Fab")
		)
		(fp_line
			(start -0.2794 0.9906)
			(end 0.2794 0.9906)
			(stroke
				(width 0.1)
				(type default)
			)
			(layer "F.Fab")
		)
		(fp_line
			(start -0.2794 -0.1016)
			(end -0.2794 0.9906)
			(stroke
				(width 0.1)
				(type default)
			)
			(layer "F.Fab")
		)
		(pad "1" smd rect
			(at 0 0 180)
			(size 0.508 0.508)
			(layers "F.Cu" "F.Mask" "F.Paste")
			(net "P3V3_STBY")
		)
		(pad "2" smd rect
			(at 0 0.889 180)
			(size 0.508 0.508)
			(layers "F.Cu" "F.Mask" "F.Paste")
			(net "RMII_BMC_OCP_TXD1_R")
		)
		(zone
			(layer "F.Cu")
			(hatch none 0.5)
			(connect_pads
				(clearance 0)
			)
			(min_thickness 0.25)
			(keepout
				(tracks not_allowed)
				(vias allowed)
				(pads allowed)
				(copperpour not_allowed)
				(footprints allowed)
			)
			(placement
				(enabled no)
				(sheetname "")
			)
			(fill
				(thermal_gap 0.5)
				(thermal_bridge_width 0.5)
				(island_removal_mode 0)
			)
			(polygon
				(pts
					(xy 403.408388 -29.125926) (xy 402.900388 -29.125926) (xy 402.900388 -28.744926) (xy 403.408388 -28.744926)
				)
			)
		)
		(zone
			(layer "F.Cu")
			(hatch none 0.5)
			(connect_pads
				(clearance 0)
			)
			(min_thickness 0.25)
			(keepout
				(tracks allowed)
				(vias not_allowed)
				(pads allowed)
				(copperpour not_allowed)
				(footprints allowed)
			)
			(placement
				(enabled no)
				(sheetname "")
			)
			(fill
				(thermal_gap 0.5)
				(thermal_bridge_width 0.5)
				(island_removal_mode 0)
			)
			(polygon
				(pts
					(xy 403.408388 -28.744926) (xy 402.900388 -28.744926) (xy 402.900388 -29.125926) (xy 403.408388 -29.125926)
				)
			)
		)
	)
	(footprint ""
		(layer "F.Cu")
		(at 404.43658 -143.561816 -90)
		(property "Reference" "C8A12"
			(at 0 0 270)
			(layer "F.SilkS")
			(hide yes)
			(effects
				(font
					(size 1.27 1.27)
				)
			)
		)
		(property "Value" ""
			(at 0 0 270)
			(layer "F.Fab")
			(effects
				(font
					(size 1.27 1.27)
				)
			)
		)
		(duplicate_pad_numbers_are_jumpers no)
		(fp_poly
			(pts
				(xy -0.7239 -0.2159) (xy 0.7239 -0.2159) (xy 0.7239 1.9939) (xy -0.7239 1.9939)
			)
			(stroke
				(width 0)
				(type default)
			)
			(fill no)
			(layer "F.CrtYd")
		)
		(fp_line
			(start -0.7239 1.9939)
			(end 0.7239 1.9939)
			(stroke
				(width 0.1)
				(type default)
			)
			(layer "F.Fab")
		)
		(fp_line
			(start 0.7239 1.9939)
			(end 0.7239 -0.2159)
			(stroke
				(width 0.1)
				(type default)
			)
			(layer "F.Fab")
		)
		(fp_line
			(start -0.7239 -0.2159)
			(end -0.7239 1.9939)
			(stroke
				(width 0.1)
				(type default)
			)
			(layer "F.Fab")
		)
		(fp_line
			(start 0.7239 -0.2159)
			(end -0.7239 -0.2159)
			(stroke
				(width 0.1)
				(type default)
			)
			(layer "F.Fab")
		)
		(pad "1" smd rect
			(at 0 0 270)
			(size 1.27 1.016)
			(layers "F.Cu" "F.Mask" "F.Paste")
			(net "P1V8_PCH_STBY")
		)
		(pad "2" smd rect
			(at 0 1.778 270)
			(size 1.27 1.016)
			(layers "F.Cu" "F.Mask" "F.Paste")
			(net "GND")
		)
		(zone
			(layer "F.Cu")
			(hatch none 0.5)
			(connect_pads
				(clearance 0)
			)
			(min_thickness 0.25)
			(keepout
				(tracks not_allowed)
				(vias allowed)
				(pads allowed)
				(copperpour not_allowed)
				(footprints allowed)
			)
			(placement
				(enabled no)
				(sheetname "")
			)
			(fill
				(thermal_gap 0.5)
				(thermal_bridge_width 0.5)
				(island_removal_mode 0)
			)
			(polygon
				(pts
					(xy 403.92858 -144.196816) (xy 403.92858 -142.926816) (xy 403.16658 -142.926816) (xy 403.16658 -144.196816)
				)
			)
		)
	)
)
